FILE_TYPE = MULTI_PHYS_TABLE;

PART 'PCA9546APW_TSSOP16'
CLASS=IC

{========================================================================================}
:CLS_PN             = JEDEC_TYPE             | ALT_SYMBOLS              | DESCRIPTION                                                | CPN_STATUS  ;
{========================================================================================}
 'G223-00050-01'    = 'SOP16_173_P0256_H043' | '(SOP16_173_P0256_H043)' | 'IC,PCA9546A,4CH_I2C-BUS_SW_W_RESET,TSSOP16'               | 'NFND'         
 'G223-10280-01'    = 'SOP16_173_P0256_H043' | '(SOP16_173_P0256_H043)' | 'IC,I2C,4CH SWITCH,9546A,2.3~5.5V,TSSOP16'                 | 'PREFERRED'
 'A223-00050-IB'    = 'SOP16_173_P0256'      | '(SOP16_173_P0256)'      | 'IC,PCA9546A,4CH_I2C-BUS_SW_W_RESET,TSSOP16,5.1X4.5X1.2MM' | ''         
 'G223-00050-02'    = 'SOP16_173_P0256'      | '(SOP16_173_P0256)'      | 'IC,PCA9546A,4CH_I2C-BUS_SW_W_RESET,TSSOP16,5.1X4.5X1.2MM' | ''         

END_PART

END.

